# SCM (Grand Teton) — schematic netlist excerpt (pin names and nets, part order shuffled) for the footprints in the layout excerpt that follows; sources: Cadence DE-HDL packaged netlist, KiCad conversion of 12092022_DA0F0TMDCD0_F0T_Management_Board_D_brd_V3_OCP.brd

C217  Q_CAP  0.1UF 25V 10% X7R  pkg 0402  page 32 : A = J7_P1 ; B = GND
PC207  Q_CAP  22UF 16V 20% X6S  pkg C0805  page 51 : A = SW_P5V_AUX_FLT ; B = GND
C56  Q_CAP  1UF 25V 10% X6S  pkg C0402  page 16 : A = P1V0_STBY_PLAVDD ; B = GND
DM1  DUMMY_SYMBOL  BMC_FLASH EMPTY  pkg TP30_FOR_BOM  page 59 : \1\ = NC

(kicad_pcb
	(version 20260206)
	(generator "pcbnew")
	(generator_version "10.0")
	(general
		(thickness 1.6)
		(legacy_teardrops no)
	)
	(paper "A4")
	(title_block
		(title "12092022_DA0F0TMDCD0_F0T_Management_Board_D_brd_V3_OCP.brd")
		(comment 1 "Grand Teton / footprints 145-148 of 1440")
	)
	(layers
		(0 "F.Cu" signal "TOP")
		(4 "In1.Cu" signal "GND")
		(6 "In2.Cu" signal "IN1")
		(8 "In3.Cu" signal "GND1")
		(10 "In4.Cu" signal "IN2")
		(12 "In5.Cu" signal "VCC")
		(14 "In6.Cu" signal "VCC1")
		(16 "In7.Cu" signal "IN3")
		(18 "In8.Cu" signal "GND2")
		(20 "In9.Cu" signal "IN4")
		(22 "In10.Cu" signal "GND3")
		(2 "B.Cu" signal "BOTTOM")
		(9 "F.Adhes" user "F.Adhesive")
		(11 "B.Adhes" user "B.Adhesive")
		(13 "F.Paste" user "Package Geometry/Pastemask Top")
		(15 "B.Paste" user "Package Geometry/Pastemask Bottom")
		(5 "F.SilkS" user "Ref Des/Silkscreen Top")
		(7 "B.SilkS" user "Ref Des/Silkscreen Bottom")
		(1 "F.Mask" user "Board Geometry/Soldermask Top")
		(3 "B.Mask" user "Board Geometry/Soldermask Bottom")
		(17 "Dwgs.User" user "User.Drawings")
		(19 "Cmts.User" user "User.Comments")
		(21 "Eco1.User" user "User.Eco1")
		(23 "Eco2.User" user "User.Eco2")
		(25 "Edge.Cuts" user "Board Geometry/Outline")
		(27 "Margin" user)
		(31 "F.CrtYd" user "Package Geometry/Place Bound Top")
		(29 "B.CrtYd" user "Package Geometry/Place Bound Bottom")
		(35 "F.Fab" user "Ref Des/Assembly Top")
		(33 "B.Fab" user "Ref Des/Assembly Bottom")
	)
	(footprint ""
		(layer "F.Cu")
		(at 9.1694 -104.6226)
		(property "Reference" "C217"
			(at 0 0 0)
			(layer "F.SilkS")
			(hide yes)
			(effects
				(font
					(size 1.27 1.27)
				)
			)
		)
		(property "Value" ""
			(at 0 0 0)
			(layer "F.Fab")
			(effects
				(font
					(size 1.27 1.27)
				)
			)
		)
		(duplicate_pad_numbers_are_jumpers no)
		(fp_line
			(start -0.7874 -0.4064)
			(end 0.7874 -0.4064)
			(stroke
				(width 0.1524)
				(type default)
			)
			(layer "F.SilkS")
		)
		(fp_line
			(start -0.7874 0.4064)
			(end -0.7874 -0.4064)
			(stroke
				(width 0.1524)
				(type default)
			)
			(layer "F.SilkS")
		)
		(fp_line
			(start 0.7874 -0.4064)
			(end 0.7874 0.4064)
			(stroke
				(width 0.1524)
				(type default)
			)
			(layer "F.SilkS")
		)
		(fp_line
			(start 0.7874 0.4064)
			(end -0.7874 0.4064)
			(stroke
				(width 0.1524)
				(type default)
			)
			(layer "F.SilkS")
		)
		(fp_line
			(start -0.67945 -0.305054)
			(end -0.12065 -0.305054)
			(stroke
				(width 0.1)
				(type default)
			)
			(layer "F.Fab")
		)
		(fp_line
			(start -0.67945 0.3048)
			(end -0.67945 -0.305054)
			(stroke
				(width 0.1)
				(type default)
			)
			(layer "F.Fab")
		)
		(fp_line
			(start -0.12065 -0.305054)
			(end -0.12065 -0.2794)
			(stroke
				(width 0.1)
				(type default)
			)
			(layer "F.Fab")
		)
		(fp_line
			(start -0.12065 -0.2794)
			(end 0.12065 -0.2794)
			(stroke
				(width 0.1)
				(type default)
			)
			(layer "F.Fab")
		)
		(fp_line
			(start -0.12065 0.2794)
			(end -0.12065 0.3048)
			(stroke
				(width 0.1)
				(type default)
			)
			(layer "F.Fab")
		)
		(fp_line
			(start -0.12065 0.3048)
			(end -0.67945 0.3048)
			(stroke
				(width 0.1)
				(type default)
			)
			(layer "F.Fab")
		)
		(fp_line
			(start 0.120396 0.2794)
			(end -0.12065 0.2794)
			(stroke
				(width 0.1)
				(type default)
			)
			(layer "F.Fab")
		)
		(fp_line
			(start 0.120396 0.3048)
			(end 0.120396 0.2794)
			(stroke
				(width 0.1)
				(type default)
			)
			(layer "F.Fab")
		)
		(fp_line
			(start 0.12065 -0.3048)
			(end 0.67945 -0.3048)
			(stroke
				(width 0.1)
				(type default)
			)
			(layer "F.Fab")
		)
		(fp_line
			(start 0.12065 -0.2794)
			(end 0.12065 -0.3048)
			(stroke
				(width 0.1)
				(type default)
			)
			(layer "F.Fab")
		)
		(fp_line
			(start 0.67945 -0.3048)
			(end 0.67945 0.3048)
			(stroke
				(width 0.1)
				(type default)
			)
			(layer "F.Fab")
		)
		(fp_line
			(start 0.67945 0.3048)
			(end 0.120396 0.3048)
			(stroke
				(width 0.1)
				(type default)
			)
			(layer "F.Fab")
		)
		(pad "1" smd circle
			(at -0.40005 0)
			(size 0 0)
			(layers "F.Cu" "F.Mask" "F.Paste")
			(net "J7_P1")
		)
		(pad "2" smd circle
			(at 0.40005 0)
			(size 0 0)
			(layers "F.Cu" "F.Mask" "F.Paste")
			(net "GND")
		)
	)
	(footprint ""
		(layer "F.Cu")
		(at 6.096 -53.594 180)
		(property "Reference" "PC207"
			(at 0 0 180)
			(layer "F.SilkS")
			(hide yes)
			(effects
				(font
					(size 1.27 1.27)
				)
			)
		)
		(property "Value" ""
			(at 0 0 180)
			(layer "F.Fab")
			(effects
				(font
					(size 1.27 1.27)
				)
			)
		)
		(duplicate_pad_numbers_are_jumpers no)
		(fp_line
			(start 1.524 0.762)
			(end -1.524 0.762)
			(stroke
				(width 0.1524)
				(type default)
			)
			(layer "F.SilkS")
		)
		(fp_line
			(start 1.524 -0.762)
			(end 1.524 0.762)
			(stroke
				(width 0.1524)
				(type default)
			)
			(layer "F.SilkS")
		)
		(fp_line
			(start -1.524 0.762)
			(end -1.524 -0.762)
			(stroke
				(width 0.1524)
				(type default)
			)
			(layer "F.SilkS")
		)
		(fp_line
			(start -1.524 -0.762)
			(end 1.524 -0.762)
			(stroke
				(width 0.1524)
				(type default)
			)
			(layer "F.SilkS")
		)
		(fp_line
			(start 1.1049 0.724916)
			(end 1.1049 -0.724916)
			(stroke
				(width 0.1)
				(type default)
			)
			(layer "F.Fab")
		)
		(fp_line
			(start 1.1049 -0.724916)
			(end -1.1049 -0.724916)
			(stroke
				(width 0.1)
				(type default)
			)
			(layer "F.Fab")
		)
		(fp_line
			(start -1.1049 0.724916)
			(end 1.1049 0.724916)
			(stroke
				(width 0.1)
				(type default)
			)
			(layer "F.Fab")
		)
		(fp_line
			(start -1.1049 -0.724916)
			(end -1.1049 0.724916)
			(stroke
				(width 0.1)
				(type default)
			)
			(layer "F.Fab")
		)
		(pad "1" smd rect
			(at -0.889 0)
			(size 1.016 1.27)
			(layers "F.Cu" "F.Mask" "F.Paste")
			(net "SW_P5V_AUX_FLT")
		)
		(pad "2" smd rect
			(at 0.889 0)
			(size 1.016 1.27)
			(layers "F.Cu" "F.Mask" "F.Paste")
			(net "GND")
		)
	)
	(footprint ""
		(layer "F.Cu")
		(at -4.251198 -136.217152)
		(property "Reference" "DM1"
			(at -0.3937 -0.588518 0)
			(unlocked yes)
			(layer "F.SilkS")
			(effects
				(font
					(size 0.254 0.127)
					(thickness 0.000001)
				)
				(justify left)
			)
		)
		(property "Value" ""
			(at 0 0 0)
			(layer "F.Fab")
			(effects
				(font
					(size 1.27 1.27)
				)
			)
		)
		(duplicate_pad_numbers_are_jumpers no)
		(pad "1" smd circle
			(at 0 0)
			(size 0.762 0.762)
			(layers "F.Cu" "F.Mask" "F.Paste")
			(net "Net_28")
		)
	)
	(footprint ""
		(layer "F.Cu")
		(at 70.023736 -37.288216 -90)
		(property "Reference" "C56"
			(at 0 0 270)
			(layer "F.SilkS")
			(hide yes)
			(effects
				(font
					(size 1.27 1.27)
				)
			)
		)
		(property "Value" ""
			(at 0 0 270)
			(layer "F.Fab")
			(effects
				(font
					(size 1.27 1.27)
				)
			)
		)
		(duplicate_pad_numbers_are_jumpers no)
		(fp_line
			(start -0.7874 0.4064)
			(end -0.7874 -0.4064)
			(stroke
				(width 0.1524)
				(type default)
			)
			(layer "F.SilkS")
		)
		(fp_line
			(start 0.7874 0.4064)
			(end -0.7874 0.4064)
			(stroke
				(width 0.1524)
				(type default)
			)
			(layer "F.SilkS")
		)
		(fp_line
			(start -0.7874 -0.4064)
			(end 0.7874 -0.4064)
			(stroke
				(width 0.1524)
				(type default)
			)
			(layer "F.SilkS")
		)
		(fp_line
			(start 0.7874 -0.4064)
			(end 0.7874 0.4064)
			(stroke
				(width 0.1524)
				(type default)
			)
			(layer "F.SilkS")
		)
		(fp_line
			(start -0.67945 0.3048)
			(end -0.67945 -0.305054)
			(stroke
				(width 0.1)
				(type default)
			)
			(layer "F.Fab")
		)
		(fp_line
			(start -0.12065 0.3048)
			(end -0.67945 0.3048)
			(stroke
				(width 0.1)
				(type default)
			)
			(layer "F.Fab")
		)
		(fp_line
			(start 0.120396 0.3048)
			(end 0.120396 0.2794)
			(stroke
				(width 0.1)
				(type default)
			)
			(layer "F.Fab")
		)
		(fp_line
			(start 0.67945 0.3048)
			(end 0.120396 0.3048)
			(stroke
				(width 0.1)
				(type default)
			)
			(layer "F.Fab")
		)
		(fp_line
			(start -0.12065 0.2794)
			(end -0.12065 0.3048)
			(stroke
				(width 0.1)
				(type default)
			)
			(layer "F.Fab")
		)
		(fp_line
			(start 0.120396 0.2794)
			(end -0.12065 0.2794)
			(stroke
				(width 0.1)
				(type default)
			)
			(layer "F.Fab")
		)
		(fp_line
			(start -0.12065 -0.2794)
			(end 0.12065 -0.2794)
			(stroke
				(width 0.1)
				(type default)
			)
			(layer "F.Fab")
		)
		(fp_line
			(start 0.12065 -0.2794)
			(end 0.12065 -0.3048)
			(stroke
				(width 0.1)
				(type default)
			)
			(layer "F.Fab")
		)
		(fp_line
			(start 0.12065 -0.3048)
			(end 0.67945 -0.3048)
			(stroke
				(width 0.1)
				(type default)
			)
			(layer "F.Fab")
		)
		(fp_line
			(start 0.67945 -0.3048)
			(end 0.67945 0.3048)
			(stroke
				(width 0.1)
				(type default)
			)
			(layer "F.Fab")
		)
		(fp_line
			(start -0.67945 -0.305054)
			(end -0.12065 -0.305054)
			(stroke
				(width 0.1)
				(type default)
			)
			(layer "F.Fab")
		)
		(fp_line
			(start -0.12065 -0.305054)
			(end -0.12065 -0.2794)
			(stroke
				(width 0.1)
				(type default)
			)
			(layer "F.Fab")
		)
		(pad "1" smd circle
			(at -0.40005 0 270)
			(size 0 0)
			(layers "F.Cu" "F.Mask" "F.Paste")
			(net "P1V0_STBY_PLAVDD")
		)
		(pad "2" smd circle
			(at 0.40005 0 270)
			(size 0 0)
			(layers "F.Cu" "F.Mask" "F.Paste")
			(net "GND")
		)
	)
)
